(kicad_pcb
	(version 20260206)
	(generator "pcbnew")
	(generator_version "10.0")
	(general
		(thickness 1.6)
		(legacy_teardrops no)
	)
	(paper "A4")
	(title_block
		(title "fcb — 12433-1M.1206WZS1330.brd")
		(comment 1 "Open Vault / Knox (Wiwynn) / footprints 269-275 of 495")
	)
	(layers
		(0 "F.Cu" signal "TOP")
		(4 "In1.Cu" signal "L2GND")
		(6 "In2.Cu" signal "L3VCC")
		(2 "B.Cu" signal "BOTTOM")
		(9 "F.Adhes" user "F.Adhesive")
		(11 "B.Adhes" user "B.Adhesive")
		(13 "F.Paste" user "Package Geometry/Pastemask Top")
		(15 "B.Paste" user "Package Geometry/Pastemask Bottom")
		(5 "F.SilkS" user "Ref Des/Silkscreen Top")
		(7 "B.SilkS" user "Ref Des/Silkscreen Bottom")
		(1 "F.Mask" user "Board Geometry/Soldermask Top")
		(3 "B.Mask" user "Board Geometry/Soldermask Bottom")
		(17 "Dwgs.User" user "User.Drawings")
		(19 "Cmts.User" user "User.Comments")
		(21 "Eco1.User" user "User.Eco1")
		(23 "Eco2.User" user "User.Eco2")
		(25 "Edge.Cuts" user "Board Geometry/Outline")
		(27 "Margin" user)
		(31 "F.CrtYd" user "Package Geometry/Place Bound Top")
		(29 "B.CrtYd" user "Package Geometry/Place Bound Bottom")
		(35 "F.Fab" user "Ref Des/Assembly Top")
		(33 "B.Fab" user "Ref Des/Assembly Bottom")
	)
	(footprint ""
		(layer "F.Cu")
		(at 8.2296 -450.6976 -90)
		(property "Reference" "R95"
			(at 0 0 270)
			(layer "F.SilkS")
			(hide yes)
			(effects
				(font
					(size 1.27 1.27)
				)
			)
		)
		(property "Value" "4K7R2F-GP"
			(at 0.064008 -3.993896 270)
			(unlocked yes)
			(layer "F.Fab")
			(hide yes)
			(effects
				(font
					(size 1.016 1.016)
					(thickness 0.1524)
				)
			)
		)
		(property "Device Type" "R402H16"
			(at 0.064008 -5.517896 270)
			(unlocked yes)
			(layer "F.Fab")
			(hide yes)
			(effects
				(font
					(size 1.016 1.016)
					(thickness 0.1524)
				)
			)
		)
		(duplicate_pad_numbers_are_jumpers no)
		(fp_line
			(start -0.508 -0.9398)
			(end -0.508 0.9398)
			(stroke
				(width 0.1524)
				(type default)
			)
			(layer "F.SilkS")
		)
		(fp_line
			(start 0.508 -0.9398)
			(end -0.508 -0.9398)
			(stroke
				(width 0.1524)
				(type default)
			)
			(layer "F.SilkS")
		)
		(fp_rect
			(start -0.508 0.9398)
			(end 0.508 -0.9398)
			(stroke
				(width 0)
				(type default)
			)
			(fill no)
			(layer "F.CrtYd")
		)
		(fp_rect
			(start -0.508 0.9398)
			(end 0.508 -0.9398)
			(stroke
				(width 0)
				(type default)
			)
			(fill no)
			(layer "F.Fab")
		)
		(pad "1" smd custom
			(at 0 -0.4445 270)
			(size 0.1397 0.1397)
			(layers "F.Cu" "F.Mask" "F.Paste")
			(net "P12V")
			(options
				(clearance outline)
				(anchor circle)
			)
			(primitives
				(gr_poly
					(pts
						(arc
							(start -0.1778 -0.2794)
							(mid -0.249642 -0.249642)
							(end -0.2794 -0.1778)
						)
						(arc
							(start -0.2794 0.1778)
							(mid -0.249642 0.249642)
							(end -0.1778 0.2794)
						)
						(arc
							(start 0.1778 0.2794)
							(mid 0.249642 0.249642)
							(end 0.2794 0.1778)
						)
						(arc
							(start 0.2794 -0.1778)
							(mid 0.249642 -0.249642)
							(end 0.1778 -0.2794)
						)
					)
					(width 0)
					(fill yes)
				)
			)
		)
		(pad "2" smd custom
			(at 0 0.4445 270)
			(size 0.1397 0.1397)
			(layers "F.Cu" "F.Mask" "F.Paste")
			(net "FAN_TACH1")
			(options
				(clearance outline)
				(anchor circle)
			)
			(primitives
				(gr_poly
					(pts
						(arc
							(start -0.1778 -0.2794)
							(mid -0.249642 -0.249642)
							(end -0.2794 -0.1778)
						)
						(arc
							(start -0.2794 0.1778)
							(mid -0.249642 0.249642)
							(end -0.1778 0.2794)
						)
						(arc
							(start 0.1778 0.2794)
							(mid 0.249642 0.249642)
							(end 0.2794 0.1778)
						)
						(arc
							(start 0.2794 -0.1778)
							(mid 0.249642 -0.249642)
							(end 0.1778 -0.2794)
						)
					)
					(width 0)
					(fill yes)
				)
			)
		)
	)
	(footprint ""
		(layer "F.Cu")
		(at 43.815 -389.001 90)
		(property "Reference" "TC9"
			(at 0 0 90)
			(layer "F.SilkS")
			(hide yes)
			(effects
				(font
					(size 1.27 1.27)
				)
			)
		)
		(property "Value" "ST68U16VDM-1-GP"
			(at 0 -9.6012 90)
			(unlocked yes)
			(layer "F.Fab")
			(hide yes)
			(effects
				(font
					(size 1.016 1.016)
					(thickness 0.1524)
				)
			)
		)
		(property "Device Type" "CT7343H79"
			(at 0 -11.1252 90)
			(unlocked yes)
			(layer "F.Fab")
			(hide yes)
			(effects
				(font
					(size 1.016 1.016)
					(thickness 0.1524)
				)
			)
		)
		(duplicate_pad_numbers_are_jumpers no)
		(fp_line
			(start 2.286 -4.8768)
			(end -2.286 -4.8768)
			(stroke
				(width 0.1524)
				(type default)
			)
			(layer "F.SilkS")
		)
		(fp_line
			(start -2.286 -4.8768)
			(end -2.286 -2.032)
			(stroke
				(width 0.1524)
				(type default)
			)
			(layer "F.SilkS")
		)
		(fp_line
			(start 2.1082 -4.699)
			(end -2.1082 -4.699)
			(stroke
				(width 0.508)
				(type default)
			)
			(layer "F.SilkS")
		)
		(fp_line
			(start 2.286 -2.032)
			(end 2.286 -4.8768)
			(stroke
				(width 0.1524)
				(type default)
			)
			(layer "F.SilkS")
		)
		(fp_line
			(start 2.286 2.032)
			(end 2.286 4.8768)
			(stroke
				(width 0.1524)
				(type default)
			)
			(layer "F.SilkS")
		)
		(fp_line
			(start 2.286 4.8768)
			(end -2.286 4.8768)
			(stroke
				(width 0.1524)
				(type default)
			)
			(layer "F.SilkS")
		)
		(fp_line
			(start -2.286 4.8768)
			(end -2.286 2.032)
			(stroke
				(width 0.1524)
				(type default)
			)
			(layer "F.SilkS")
		)
		(fp_rect
			(start -2.1463 3.6449)
			(end 2.1463 -3.6449)
			(stroke
				(width 0)
				(type default)
			)
			(fill no)
			(layer "F.CrtYd")
		)
		(fp_poly
			(pts
				(xy -2.54 4.953) (xy -2.54 4.2926) (xy -3.81 4.2926) (xy -3.81 -4.2926) (xy -2.54 -4.2926) (xy -2.54 -4.953)
				(xy 2.54 -4.953) (xy 2.54 -4.2926) (xy 3.81 -4.2926) (xy 3.81 -1.6256) (xy 2.1463 -1.6256) (xy 2.1463 -3.6449)
				(xy -2.1463 -3.6449) (xy -2.1463 3.6449) (xy 2.1463 3.6449) (xy 2.1463 -1.6129) (xy 3.81 -1.6129)
				(xy 3.81 4.2926) (xy 2.54 4.2926) (xy 2.54 4.953)
			)
			(stroke
				(width 0)
				(type default)
			)
			(fill no)
			(layer "F.CrtYd")
		)
		(fp_rect
			(start 2.54 4.2926)
			(end 3.81 -4.2926)
			(stroke
				(width 0)
				(type default)
			)
			(fill no)
			(layer "F.Fab")
		)
		(fp_rect
			(start -3.81 4.2926)
			(end -2.54 -4.2926)
			(stroke
				(width 0)
				(type default)
			)
			(fill no)
			(layer "F.Fab")
		)
		(fp_rect
			(start -2.54 4.953)
			(end 2.54 -4.953)
			(stroke
				(width 0)
				(type default)
			)
			(fill no)
			(layer "F.Fab")
		)
		(pad "1" smd rect
			(at 0 -3.1496 90)
			(size 2.413 2.286)
			(layers "F.Cu" "F.Mask" "F.Paste")
			(net "P12V")
		)
		(pad "2" smd rect
			(at 0 3.1496 90)
			(size 2.413 2.286)
			(layers "F.Cu" "F.Mask" "F.Paste")
			(net "GND")
		)
		(zone
			(layer "F.Cu")
			(hatch none 0.5)
			(connect_pads
				(clearance 0)
			)
			(min_thickness 0.25)
			(keepout
				(tracks allowed)
				(vias not_allowed)
				(pads allowed)
				(copperpour not_allowed)
				(footprints allowed)
			)
			(placement
				(enabled no)
				(sheetname "")
			)
			(fill
				(thermal_gap 0.5)
				(thermal_bridge_width 0.5)
				(island_removal_mode 0)
			)
			(polygon
				(pts
					(xy 42.1259 -390.5123) (xy 39.2176 -390.5123) (xy 39.2176 -387.4897) (xy 42.1132 -387.4897) (xy 42.4434 -387.4897)
					(xy 42.4434 -390.5123)
				)
			)
		)
		(zone
			(layer "F.Cu")
			(hatch none 0.5)
			(connect_pads
				(clearance 0)
			)
			(min_thickness 0.25)
			(keepout
				(tracks allowed)
				(vias not_allowed)
				(pads allowed)
				(copperpour not_allowed)
				(footprints allowed)
			)
			(placement
				(enabled no)
				(sheetname "")
			)
			(fill
				(thermal_gap 0.5)
				(thermal_bridge_width 0.5)
				(island_removal_mode 0)
			)
			(polygon
				(pts
					(xy 48.4124 -387.4897) (xy 48.4124 -390.5123) (xy 45.5168 -390.5123) (xy 45.1866 -390.5123) (xy 45.1866 -387.4897)
					(xy 45.5168 -387.4897)
				)
			)
		)
	)
	(footprint ""
		(layer "F.Cu")
		(at 22.225 -222.416116 180)
		(property "Reference" "C16"
			(at 0 0 180)
			(layer "F.SilkS")
			(hide yes)
			(effects
				(font
					(size 1.27 1.27)
				)
			)
		)
		(property "Value" "SCD1U50V3KX-GP"
			(at 0 -2.8194 180)
			(unlocked yes)
			(layer "F.Fab")
			(hide yes)
			(effects
				(font
					(size 1.016 1.016)
					(thickness 0.1524)
				)
			)
		)
		(property "Device Type" "C603H36"
			(at 0 -4.3434 180)
			(unlocked yes)
			(layer "F.Fab")
			(hide yes)
			(effects
				(font
					(size 1.016 1.016)
					(thickness 0.1524)
				)
			)
		)
		(duplicate_pad_numbers_are_jumpers no)
		(fp_line
			(start 0.508 0)
			(end -0.508 0)
			(stroke
				(width 0.2032)
				(type default)
			)
			(layer "F.SilkS")
		)
		(fp_rect
			(start -0.5842 1.3335)
			(end 0.5842 -1.3335)
			(stroke
				(width 0)
				(type default)
			)
			(fill no)
			(layer "F.CrtYd")
		)
		(fp_rect
			(start -0.5842 1.3335)
			(end 0.5842 -1.3335)
			(stroke
				(width 0)
				(type default)
			)
			(fill no)
			(layer "F.Fab")
		)
		(pad "1" smd custom
			(at 0 -0.762 180)
			(size 0.2159 0.2159)
			(layers "F.Cu" "F.Mask" "F.Paste")
			(net "P3V3")
			(options
				(clearance outline)
				(anchor circle)
			)
			(primitives
				(gr_poly
					(pts
						(arc
							(start -0.3302 -0.4318)
							(mid -0.402042 -0.402042)
							(end -0.4318 -0.3302)
						)
						(arc
							(start -0.4318 0.3302)
							(mid -0.402042 0.402042)
							(end -0.3302 0.4318)
						)
						(arc
							(start 0.3302 0.4318)
							(mid 0.402042 0.402042)
							(end 0.4318 0.3302)
						)
						(arc
							(start 0.4318 -0.3302)
							(mid 0.402042 -0.402042)
							(end 0.3302 -0.4318)
						)
					)
					(width 0)
					(fill yes)
				)
			)
		)
		(pad "2" smd custom
			(at 0 0.762 180)
			(size 0.2159 0.2159)
			(layers "F.Cu" "F.Mask" "F.Paste")
			(net "GND")
			(options
				(clearance outline)
				(anchor circle)
			)
			(primitives
				(gr_poly
					(pts
						(arc
							(start -0.3302 -0.4318)
							(mid -0.402042 -0.402042)
							(end -0.4318 -0.3302)
						)
						(arc
							(start -0.4318 0.3302)
							(mid -0.402042 0.402042)
							(end -0.3302 0.4318)
						)
						(arc
							(start 0.3302 0.4318)
							(mid 0.402042 0.402042)
							(end 0.4318 0.3302)
						)
						(arc
							(start 0.4318 -0.3302)
							(mid 0.402042 -0.402042)
							(end 0.3302 -0.4318)
						)
					)
					(width 0)
					(fill yes)
				)
			)
		)
	)
	(footprint ""
		(layer "F.Cu")
		(at 41.7576 -158.1658 90)
		(property "Reference" "R50"
			(at 0 0 90)
			(layer "F.SilkS")
			(hide yes)
			(effects
				(font
					(size 1.27 1.27)
				)
			)
		)
		(property "Value" "0R2J-2-GP"
			(at 0.064008 -3.993896 90)
			(unlocked yes)
			(layer "F.Fab")
			(hide yes)
			(effects
				(font
					(size 1.016 1.016)
					(thickness 0.1524)
				)
			)
		)
		(property "Device Type" "R402H16"
			(at 0.064008 -5.517896 90)
			(unlocked yes)
			(layer "F.Fab")
			(hide yes)
			(effects
				(font
					(size 1.016 1.016)
					(thickness 0.1524)
				)
			)
		)
		(duplicate_pad_numbers_are_jumpers no)
		(fp_line
			(start 0.508 -0.9398)
			(end -0.508 -0.9398)
			(stroke
				(width 0.1524)
				(type default)
			)
			(layer "F.SilkS")
		)
		(fp_line
			(start -0.508 -0.9398)
			(end -0.508 0.9398)
			(stroke
				(width 0.1524)
				(type default)
			)
			(layer "F.SilkS")
		)
		(fp_rect
			(start -0.508 0.9398)
			(end 0.508 -0.9398)
			(stroke
				(width 0)
				(type default)
			)
			(fill no)
			(layer "F.CrtYd")
		)
		(fp_rect
			(start -0.508 0.9398)
			(end 0.508 -0.9398)
			(stroke
				(width 0)
				(type default)
			)
			(fill no)
			(layer "F.Fab")
		)
		(pad "1" smd custom
			(at 0 -0.4445 90)
			(size 0.1397 0.1397)
			(layers "F.Cu" "F.Mask" "F.Paste")
			(net "NCT7904_VSEN1")
			(options
				(clearance outline)
				(anchor circle)
			)
			(primitives
				(gr_poly
					(pts
						(arc
							(start -0.1778 -0.2794)
							(mid -0.249642 -0.249642)
							(end -0.2794 -0.1778)
						)
						(arc
							(start -0.2794 0.1778)
							(mid -0.249642 0.249642)
							(end -0.1778 0.2794)
						)
						(arc
							(start 0.1778 0.2794)
							(mid 0.249642 0.249642)
							(end 0.2794 0.1778)
						)
						(arc
							(start 0.2794 -0.1778)
							(mid 0.249642 -0.249642)
							(end 0.1778 -0.2794)
						)
					)
					(width 0)
					(fill yes)
				)
			)
		)
		(pad "2" smd custom
			(at 0 0.4445 90)
			(size 0.1397 0.1397)
			(layers "F.Cu" "F.Mask" "F.Paste")
			(net "NCT7904_VSEN_P12V_AUX")
			(options
				(clearance outline)
				(anchor circle)
			)
			(primitives
				(gr_poly
					(pts
						(arc
							(start -0.1778 -0.2794)
							(mid -0.249642 -0.249642)
							(end -0.2794 -0.1778)
						)
						(arc
							(start -0.2794 0.1778)
							(mid -0.249642 0.249642)
							(end -0.1778 0.2794)
						)
						(arc
							(start 0.1778 0.2794)
							(mid 0.249642 0.249642)
							(end 0.2794 0.1778)
						)
						(arc
							(start 0.2794 -0.1778)
							(mid 0.249642 -0.249642)
							(end 0.1778 -0.2794)
						)
					)
					(width 0)
					(fill yes)
				)
			)
		)
	)
	(footprint ""
		(layer "F.Cu")
		(at 13.081 -448.2338 90)
		(property "Reference" "R101"
			(at 0 0 90)
			(layer "F.SilkS")
			(hide yes)
			(effects
				(font
					(size 1.27 1.27)
				)
			)
		)
		(property "Value" "27KR3F-GP"
			(at -0.0254 -2.5146 90)
			(unlocked yes)
			(layer "F.Fab")
			(hide yes)
			(effects
				(font
					(size 1.016 1.016)
					(thickness 0.1524)
				)
			)
		)
		(property "Device Type" "R603H22"
			(at -0.0254 -4.0386 90)
			(unlocked yes)
			(layer "F.Fab")
			(hide yes)
			(effects
				(font
					(size 1.016 1.016)
					(thickness 0.1524)
				)
			)
		)
		(duplicate_pad_numbers_are_jumpers no)
		(fp_line
			(start 0.2032 0)
			(end 0.4826 0)
			(stroke
				(width 0.2032)
				(type default)
			)
			(layer "F.SilkS")
		)
		(fp_line
			(start -0.4826 0)
			(end -0.2032 0)
			(stroke
				(width 0.2032)
				(type default)
			)
			(layer "F.SilkS")
		)
		(fp_rect
			(start -0.5842 1.3335)
			(end 0.5842 -1.3335)
			(stroke
				(width 0)
				(type default)
			)
			(fill no)
			(layer "F.CrtYd")
		)
		(fp_rect
			(start -0.5842 1.3335)
			(end 0.5842 -1.3335)
			(stroke
				(width 0)
				(type default)
			)
			(fill no)
			(layer "F.Fab")
		)
		(pad "1" smd custom
			(at 0 -0.762 90)
			(size 0.2159 0.2159)
			(layers "F.Cu" "F.Mask" "F.Paste")
			(net "FAN_TACH2")
			(options
				(clearance outline)
				(anchor circle)
			)
			(primitives
				(gr_poly
					(pts
						(arc
							(start -0.3302 -0.4318)
							(mid -0.402042 -0.402042)
							(end -0.4318 -0.3302)
						)
						(arc
							(start -0.4318 0.3302)
							(mid -0.402042 0.402042)
							(end -0.3302 0.4318)
						)
						(arc
							(start 0.3302 0.4318)
							(mid 0.402042 0.402042)
							(end 0.4318 0.3302)
						)
						(arc
							(start 0.4318 -0.3302)
							(mid 0.402042 -0.402042)
							(end 0.3302 -0.4318)
						)
					)
					(width 0)
					(fill yes)
				)
			)
		)
		(pad "2" smd custom
			(at 0 0.762 90)
			(size 0.2159 0.2159)
			(layers "F.Cu" "F.Mask" "F.Paste")
			(net "FANIN_2")
			(options
				(clearance outline)
				(anchor circle)
			)
			(primitives
				(gr_poly
					(pts
						(arc
							(start -0.3302 -0.4318)
							(mid -0.402042 -0.402042)
							(end -0.4318 -0.3302)
						)
						(arc
							(start -0.4318 0.3302)
							(mid -0.402042 0.402042)
							(end -0.3302 0.4318)
						)
						(arc
							(start 0.3302 0.4318)
							(mid 0.402042 0.402042)
							(end 0.4318 0.3302)
						)
						(arc
							(start 0.4318 -0.3302)
							(mid 0.402042 -0.402042)
							(end 0.3302 -0.4318)
						)
					)
					(width 0)
					(fill yes)
				)
			)
		)
	)
	(footprint ""
		(layer "F.Cu")
		(at 36.5252 -254.381)
		(property "Reference" "R48"
			(at 0 0 0)
			(layer "F.SilkS")
			(hide yes)
			(effects
				(font
					(size 1.27 1.27)
				)
			)
		)
		(property "Value" "4K7R2J-2-GP"
			(at 0.064008 -3.993896 0)
			(unlocked yes)
			(layer "F.Fab")
			(hide yes)
			(effects
				(font
					(size 1.016 1.016)
					(thickness 0.1524)
				)
			)
		)
		(property "Device Type" "R402H16"
			(at 0.064008 -5.517896 0)
			(unlocked yes)
			(layer "F.Fab")
			(hide yes)
			(effects
				(font
					(size 1.016 1.016)
					(thickness 0.1524)
				)
			)
		)
		(duplicate_pad_numbers_are_jumpers no)
		(fp_line
			(start -0.508 -0.9398)
			(end -0.508 0.9398)
			(stroke
				(width 0.1524)
				(type default)
			)
			(layer "F.SilkS")
		)
		(fp_line
			(start 0.508 -0.9398)
			(end -0.508 -0.9398)
			(stroke
				(width 0.1524)
				(type default)
			)
			(layer "F.SilkS")
		)
		(fp_rect
			(start -0.508 0.9398)
			(end 0.508 -0.9398)
			(stroke
				(width 0)
				(type default)
			)
			(fill no)
			(layer "F.CrtYd")
		)
		(fp_rect
			(start -0.508 0.9398)
			(end 0.508 -0.9398)
			(stroke
				(width 0)
				(type default)
			)
			(fill no)
			(layer "F.Fab")
		)
		(pad "1" smd custom
			(at 0 -0.4445)
			(size 0.1397 0.1397)
			(layers "F.Cu" "F.Mask" "F.Paste")
			(net "P3V3")
			(options
				(clearance outline)
				(anchor circle)
			)
			(primitives
				(gr_poly
					(pts
						(arc
							(start -0.1778 -0.2794)
							(mid -0.249642 -0.249642)
							(end -0.2794 -0.1778)
						)
						(arc
							(start -0.2794 0.1778)
							(mid -0.249642 0.249642)
							(end -0.1778 0.2794)
						)
						(arc
							(start 0.1778 0.2794)
							(mid 0.249642 0.249642)
							(end 0.2794 0.1778)
						)
						(arc
							(start 0.2794 -0.1778)
							(mid 0.249642 -0.249642)
							(end 0.1778 -0.2794)
						)
					)
					(width 0)
					(fill yes)
				)
			)
		)
		(pad "2" smd custom
			(at 0 0.4445)
			(size 0.1397 0.1397)
			(layers "F.Cu" "F.Mask" "F.Paste")
			(net "LED_DRV_RST")
			(options
				(clearance outline)
				(anchor circle)
			)
			(primitives
				(gr_poly
					(pts
						(arc
							(start -0.1778 -0.2794)
							(mid -0.249642 -0.249642)
							(end -0.2794 -0.1778)
						)
						(arc
							(start -0.2794 0.1778)
							(mid -0.249642 0.249642)
							(end -0.1778 0.2794)
						)
						(arc
							(start 0.1778 0.2794)
							(mid 0.249642 0.249642)
							(end 0.2794 0.1778)
						)
						(arc
							(start 0.2794 -0.1778)
							(mid 0.249642 -0.249642)
							(end 0.1778 -0.2794)
						)
					)
					(width 0)
					(fill yes)
				)
			)
		)
	)
	(footprint ""
		(layer "F.Cu")
		(at 18.7706 -141.5034 180)
		(property "Reference" "PR106"
			(at 0 0 180)
			(layer "F.SilkS")
			(hide yes)
			(effects
				(font
					(size 1.27 1.27)
				)
			)
		)
		(property "Value" "1KR2F-3-GP"
			(at 0.064008 -3.993896 180)
			(unlocked yes)
			(layer "F.Fab")
			(hide yes)
			(effects
				(font
					(size 1.016 1.016)
					(thickness 0.1524)
				)
			)
		)
		(property "Device Type" "R402H16"
			(at 0.064008 -5.517896 180)
			(unlocked yes)
			(layer "F.Fab")
			(hide yes)
			(effects
				(font
					(size 1.016 1.016)
					(thickness 0.1524)
				)
			)
		)
		(duplicate_pad_numbers_are_jumpers no)
		(fp_line
			(start 0.508 -0.9398)
			(end -0.508 -0.9398)
			(stroke
				(width 0.1524)
				(type default)
			)
			(layer "F.SilkS")
		)
		(fp_line
			(start -0.508 -0.9398)
			(end -0.508 0.9398)
			(stroke
				(width 0.1524)
				(type default)
			)
			(layer "F.SilkS")
		)
		(fp_rect
			(start -0.508 0.9398)
			(end 0.508 -0.9398)
			(stroke
				(width 0)
				(type default)
			)
			(fill no)
			(layer "F.CrtYd")
		)
		(fp_rect
			(start -0.508 0.9398)
			(end 0.508 -0.9398)
			(stroke
				(width 0)
				(type default)
			)
			(fill no)
			(layer "F.Fab")
		)
		(pad "1" smd custom
			(at 0 -0.4445 180)
			(size 0.1397 0.1397)
			(layers "F.Cu" "F.Mask" "F.Paste")
			(net "P12VU_2490_PG")
			(options
				(clearance outline)
				(anchor circle)
			)
			(primitives
				(gr_poly
					(pts
						(arc
							(start -0.1778 -0.2794)
							(mid -0.249642 -0.249642)
							(end -0.2794 -0.1778)
						)
						(arc
							(start -0.2794 0.1778)
							(mid -0.249642 0.249642)
							(end -0.1778 0.2794)
						)
						(arc
							(start 0.1778 0.2794)
							(mid 0.249642 0.249642)
							(end 0.2794 0.1778)
						)
						(arc
							(start 0.2794 -0.1778)
							(mid 0.249642 -0.249642)
							(end 0.1778 -0.2794)
						)
					)
					(width 0)
					(fill yes)
				)
			)
		)
		(pad "2" smd custom
			(at 0 0.4445 180)
			(size 0.1397 0.1397)
			(layers "F.Cu" "F.Mask" "F.Paste")
			(net "GND")
			(options
				(clearance outline)
				(anchor circle)
			)
			(primitives
				(gr_poly
					(pts
						(arc
							(start -0.1778 -0.2794)
							(mid -0.249642 -0.249642)
							(end -0.2794 -0.1778)
						)
						(arc
							(start -0.2794 0.1778)
							(mid -0.249642 0.249642)
							(end -0.1778 0.2794)
						)
						(arc
							(start 0.1778 0.2794)
							(mid 0.249642 0.249642)
							(end 0.2794 0.1778)
						)
						(arc
							(start 0.2794 -0.1778)
							(mid 0.249642 -0.249642)
							(end 0.1778 -0.2794)
						)
					)
					(width 0)
					(fill yes)
				)
			)
		)
	)
)
